(kicad_pcb
	(version 20260206)
	(generator "pcbnew")
	(generator_version "10.0")
	(general
		(thickness 1.6)
		(legacy_teardrops no)
	)
	(paper "A4")
	(title_block
		(title "v1-pdb — T6M_PDB_D_0927_0900.brd")
		(comment 1 "Open CloudServer (Microsoft) / footprints 136-138 of 321")
	)
	(layers
		(0 "F.Cu" signal "TOP")
		(4 "In1.Cu" signal "GND")
		(6 "In2.Cu" signal "IN1")
		(8 "In3.Cu" signal "VCC")
		(10 "In4.Cu" signal "VCC1")
		(12 "In5.Cu" signal "IN2")
		(14 "In6.Cu" signal "GND1")
		(2 "B.Cu" signal "BOTTOM")
		(9 "F.Adhes" user "F.Adhesive")
		(11 "B.Adhes" user "B.Adhesive")
		(13 "F.Paste" user "Package Geometry/Pastemask Top")
		(15 "B.Paste" user "Package Geometry/Pastemask Bottom")
		(5 "F.SilkS" user "Ref Des/Silkscreen Top")
		(7 "B.SilkS" user "Ref Des/Silkscreen Bottom")
		(1 "F.Mask" user "Board Geometry/Soldermask Top")
		(3 "B.Mask" user "Board Geometry/Soldermask Bottom")
		(17 "Dwgs.User" user "User.Drawings")
		(19 "Cmts.User" user "User.Comments")
		(21 "Eco1.User" user "User.Eco1")
		(23 "Eco2.User" user "User.Eco2")
		(25 "Edge.Cuts" user "Board Geometry/Outline")
		(27 "Margin" user)
		(31 "F.CrtYd" user "Package Geometry/Place Bound Top")
		(29 "B.CrtYd" user "Package Geometry/Place Bound Bottom")
		(35 "F.Fab" user "Ref Des/Assembly Top")
		(33 "B.Fab" user "Ref Des/Assembly Bottom")
	)
	(footprint ""
		(layer "F.Cu")
		(at 4.50469 -105.621836)
		(property "Reference" "J27"
			(at -3.5179 -4.511548 0)
			(unlocked yes)
			(layer "F.SilkS")
			(effects
				(font
					(size 0.7874 0.5842)
					(thickness 0.1524)
				)
				(justify left)
			)
		)
		(property "Value" ""
			(at 0 0 0)
			(layer "F.Fab")
			(effects
				(font
					(size 1.27 1.27)
				)
			)
		)
		(duplicate_pad_numbers_are_jumpers no)
		(fp_line
			(start -3.370072 -3.81)
			(end 12.260072 -3.81)
			(stroke
				(width 0.1524)
				(type default)
			)
			(layer "F.SilkS")
		)
		(fp_line
			(start -3.370072 12.830048)
			(end -3.370072 -3.81)
			(stroke
				(width 0.1524)
				(type default)
			)
			(layer "F.SilkS")
		)
		(fp_line
			(start 12.260072 -3.81)
			(end 12.260072 12.830048)
			(stroke
				(width 0.1524)
				(type default)
			)
			(layer "F.SilkS")
		)
		(fp_line
			(start 12.260072 12.830048)
			(end -3.370072 12.830048)
			(stroke
				(width 0.1524)
				(type default)
			)
			(layer "F.SilkS")
		)
		(fp_poly
			(pts
				(xy -0.073914 -4.222496) (xy -0.7874 -5.649468) (xy 0.639572 -5.649468)
			)
			(stroke
				(width 0)
				(type default)
			)
			(fill yes)
			(layer "F.SilkS")
		)
		(fp_poly
			(pts
				(xy -0.762 0.762) (xy 8.382 0.762) (xy 8.382 -1.8034) (xy 9.652 -1.8034) (xy 9.652 -3.302) (xy 0.508 -3.302)
				(xy 0.508 -0.762) (xy -0.762 -0.762)
			)
			(stroke
				(width 0)
				(type default)
			)
			(fill no)
			(layer "B.CrtYd")
		)
		(fp_poly
			(pts
				(arc
					(start 0.6604 6.35)
					(mid -3.2004 6.35)
					(end 0.6604 6.35)
				)
			)
			(stroke
				(width 0)
				(type default)
			)
			(fill no)
			(layer "B.CrtYd")
		)
		(fp_poly
			(pts
				(arc
					(start 12.0904 6.35)
					(mid 8.2296 6.35)
					(end 12.0904 6.35)
				)
			)
			(stroke
				(width 0)
				(type default)
			)
			(fill no)
			(layer "B.CrtYd")
		)
		(fp_poly
			(pts
				(xy -3.370072 12.830048) (xy 12.260072 12.830048) (xy 12.260072 -3.81) (xy -3.370072 -3.81)
			)
			(stroke
				(width 0)
				(type default)
			)
			(fill no)
			(layer "F.CrtYd")
		)
		(fp_line
			(start -3.370072 -3.81)
			(end 12.260072 -3.81)
			(stroke
				(width 0.1)
				(type default)
			)
			(layer "F.Fab")
		)
		(fp_line
			(start -3.370072 12.830048)
			(end -3.370072 -3.81)
			(stroke
				(width 0.1)
				(type default)
			)
			(layer "F.Fab")
		)
		(fp_line
			(start 12.260072 -3.81)
			(end 12.260072 12.830048)
			(stroke
				(width 0.1)
				(type default)
			)
			(layer "F.Fab")
		)
		(fp_line
			(start 12.260072 12.830048)
			(end -3.370072 12.830048)
			(stroke
				(width 0.1)
				(type default)
			)
			(layer "F.Fab")
		)
		(fp_poly
			(pts
				(xy -3.576828 0) (xy -5.0038 0.713486) (xy -5.0038 -0.713486)
			)
			(stroke
				(width 0)
				(type default)
			)
			(fill yes)
			(layer "F.Fab")
		)
		(fp_text user "2"
			(at -3.9624 -2.428748 0)
			(unlocked yes)
			(layer "F.SilkS")
			(effects
				(font
					(size 0.7874 0.5842)
					(thickness 0.1524)
				)
			)
		)
		(fp_text user "1"
			(at -3.9116 -0.930148 0)
			(unlocked yes)
			(layer "F.SilkS")
			(effects
				(font
					(size 0.7874 0.5842)
					(thickness 0.1524)
				)
			)
		)
		(fp_text user "8"
			(at 12.7762 -2.555748 0)
			(unlocked yes)
			(layer "F.SilkS")
			(effects
				(font
					(size 0.7874 0.5842)
					(thickness 0.1524)
				)
			)
		)
		(fp_text user "7"
			(at 12.7762 -0.091948 0)
			(unlocked yes)
			(layer "F.SilkS")
			(effects
				(font
					(size 0.7874 0.5842)
					(thickness 0.1524)
				)
			)
		)
		(fp_text user "1"
			(at -1.2954 0.085852 0)
			(unlocked yes)
			(layer "B.SilkS")
			(effects
				(font
					(size 0.7874 0.5842)
					(thickness 0.1524)
				)
				(justify mirror)
			)
		)
		(fp_text user "2"
			(at 0 -2.581148 0)
			(unlocked yes)
			(layer "B.SilkS")
			(effects
				(font
					(size 0.7874 0.5842)
					(thickness 0.1524)
				)
				(justify mirror)
			)
		)
		(fp_text user "7"
			(at 8.8138 0.238252 0)
			(unlocked yes)
			(layer "B.SilkS")
			(effects
				(font
					(size 0.7874 0.5842)
					(thickness 0.1524)
				)
				(justify mirror)
			)
		)
		(fp_text user "8"
			(at 10.0838 -2.403348 0)
			(unlocked yes)
			(layer "B.SilkS")
			(effects
				(font
					(size 0.7874 0.5842)
					(thickness 0.1524)
				)
				(justify mirror)
			)
		)
		(fp_text user "1"
			(at -1.2954 0.085852 0)
			(unlocked yes)
			(layer "B.Fab")
			(effects
				(font
					(size 0.7874 0.5842)
					(thickness 0.000001)
				)
				(justify mirror)
			)
		)
		(fp_text user "2"
			(at 0 -2.581148 0)
			(unlocked yes)
			(layer "B.Fab")
			(effects
				(font
					(size 0.7874 0.5842)
					(thickness 0.000001)
				)
				(justify mirror)
			)
		)
		(fp_text user "7"
			(at 8.8138 0.238252 0)
			(unlocked yes)
			(layer "B.Fab")
			(effects
				(font
					(size 0.7874 0.5842)
					(thickness 0.000001)
				)
				(justify mirror)
			)
		)
		(fp_text user "8"
			(at 10.0838 -2.403348 0)
			(unlocked yes)
			(layer "B.Fab")
			(effects
				(font
					(size 0.7874 0.5842)
					(thickness 0.000001)
				)
				(justify mirror)
			)
		)
		(fp_text user "2"
			(at -3.9624 -2.428748 0)
			(unlocked yes)
			(layer "F.Fab")
			(effects
				(font
					(size 0.7874 0.5842)
					(thickness 0.000001)
				)
			)
		)
		(fp_text user "1"
			(at -3.9116 -0.930148 0)
			(unlocked yes)
			(layer "F.Fab")
			(effects
				(font
					(size 0.7874 0.5842)
					(thickness 0.000001)
				)
			)
		)
		(fp_text user "8"
			(at 12.7762 -2.555748 0)
			(unlocked yes)
			(layer "F.Fab")
			(effects
				(font
					(size 0.7874 0.5842)
					(thickness 0.000001)
				)
			)
		)
		(fp_text user "7"
			(at 12.7762 -0.091948 0)
			(unlocked yes)
			(layer "F.Fab")
			(effects
				(font
					(size 0.7874 0.5842)
					(thickness 0.000001)
				)
			)
		)
		(pad "" np_thru_hole circle
			(at -1.27 6.35)
			(size 3.3528 3.3528)
			(drill 3.3528)
			(layers "*.Cu" "*.Mask")
			(clearance 0.381)
			(thermal_gap 0.381)
		)
		(pad "" np_thru_hole circle
			(at 10.16 6.35)
			(size 3.3528 3.3528)
			(drill 3.3528)
			(layers "*.Cu" "*.Mask")
			(clearance 0.381)
			(thermal_gap 0.381)
		)
		(pad "1" thru_hole rect
			(at 0 0)
			(size 1.397 1.397)
			(drill 0.9906)
			(layers "*.Cu" "*.Mask")
			(remove_unused_layers no)
			(net "UART_RTS_P6_L_N")
			(clearance 0.0508)
			(thermal_gap 0.0508)
			(padstack
				(mode front_inner_back)
				(layer "Inner"
					(shape circle)
					(size 1.397 1.397)
					(clearance 0.0508)
				)
				(layer "B.Cu"
					(shape rect)
					(size 1.397 1.397)
					(clearance 0.0508)
				)
			)
		)
		(pad "2" thru_hole circle
			(at 1.27 -2.54)
			(size 1.397 1.397)
			(drill 0.9906)
			(layers "*.Cu" "*.Mask")
			(remove_unused_layers no)
			(net "UART_DSR_P6_L_N")
			(clearance 0.0508)
			(thermal_gap 0.0508)
		)
		(pad "3" thru_hole circle
			(at 2.54 0)
			(size 1.397 1.397)
			(drill 0.9906)
			(layers "*.Cu" "*.Mask")
			(remove_unused_layers no)
			(net "UART_RX_P6_L")
			(clearance 0.0508)
			(thermal_gap 0.0508)
		)
		(pad "4" thru_hole circle
			(at 3.81 -2.54)
			(size 1.397 1.397)
			(drill 0.9906)
			(layers "*.Cu" "*.Mask")
			(remove_unused_layers no)
			(net "UART_RI_P6_L_N")
			(clearance 0.0508)
			(thermal_gap 0.0508)
		)
		(pad "5" thru_hole circle
			(at 5.08 0)
			(size 1.397 1.397)
			(drill 0.9906)
			(layers "*.Cu" "*.Mask")
			(remove_unused_layers no)
			(net "GND")
			(clearance 0.0508)
			(thermal_gap 0.0508)
		)
		(pad "6" thru_hole circle
			(at 6.35 -2.54)
			(size 1.397 1.397)
			(drill 0.9906)
			(layers "*.Cu" "*.Mask")
			(remove_unused_layers no)
			(net "UART_TX_P6_L")
			(clearance 0.0508)
			(thermal_gap 0.0508)
		)
		(pad "7" thru_hole circle
			(at 7.62 0)
			(size 1.397 1.397)
			(drill 0.9906)
			(layers "*.Cu" "*.Mask")
			(remove_unused_layers no)
			(net "UART_DTR_P6_L_N")
			(clearance 0.0508)
			(thermal_gap 0.0508)
		)
		(pad "8" thru_hole circle
			(at 8.89 -2.54)
			(size 1.397 1.397)
			(drill 0.9906)
			(layers "*.Cu" "*.Mask")
			(remove_unused_layers no)
			(net "UART_CTS_P6_L_N")
			(clearance 0.0508)
			(thermal_gap 0.0508)
		)
		(zone
			(layers "F.Cu" "B.Cu" "In1.Cu" "In2.Cu" "In3.Cu" "In4.Cu" "In5.Cu" "In6.Cu")
			(hatch none 0.5)
			(connect_pads
				(clearance 0)
			)
			(min_thickness 0.25)
			(keepout
				(tracks not_allowed)
				(vias allowed)
				(pads allowed)
				(copperpour not_allowed)
				(footprints allowed)
			)
			(placement
				(enabled no)
				(sheetname "")
			)
			(fill
				(thermal_gap 0.5)
				(thermal_bridge_width 0.5)
				(island_removal_mode 0)
			)
			(polygon
				(pts
					(arc
						(start 5.31749 -99.271836)
						(mid 1.15189 -99.271836)
						(end 5.31749 -99.271836)
					)
				)
			)
		)
		(zone
			(layers "F.Cu" "B.Cu" "In1.Cu" "In2.Cu" "In3.Cu" "In4.Cu" "In5.Cu" "In6.Cu")
			(hatch none 0.5)
			(connect_pads
				(clearance 0)
			)
			(min_thickness 0.25)
			(keepout
				(tracks not_allowed)
				(vias allowed)
				(pads allowed)
				(copperpour not_allowed)
				(footprints allowed)
			)
			(placement
				(enabled no)
				(sheetname "")
			)
			(fill
				(thermal_gap 0.5)
				(thermal_bridge_width 0.5)
				(island_removal_mode 0)
			)
			(polygon
				(pts
					(arc
						(start 16.74749 -99.271836)
						(mid 12.58189 -99.271836)
						(end 16.74749 -99.271836)
					)
				)
			)
		)
	)
	(footprint ""
		(layer "F.Cu")
		(at 27.28468 -5.10032)
		(property "Reference" "R45"
			(at -1.676146 2.569972 0)
			(unlocked yes)
			(layer "F.SilkS")
			(effects
				(font
					(size 0.7874 0.5842)
					(thickness 0.1524)
				)
				(justify left)
			)
		)
		(property "Value" ""
			(at 0 0 0)
			(layer "F.Fab")
			(effects
				(font
					(size 1.27 1.27)
				)
			)
		)
		(duplicate_pad_numbers_are_jumpers no)
		(fp_line
			(start -0.7874 -0.4064)
			(end 0.7874 -0.4064)
			(stroke
				(width 0.1524)
				(type default)
			)
			(layer "F.SilkS")
		)
		(fp_line
			(start -0.7874 0.4064)
			(end -0.7874 -0.4064)
			(stroke
				(width 0.1524)
				(type default)
			)
			(layer "F.SilkS")
		)
		(fp_line
			(start 0.7874 -0.4064)
			(end 0.7874 0.4064)
			(stroke
				(width 0.1524)
				(type default)
			)
			(layer "F.SilkS")
		)
		(fp_line
			(start 0.7874 0.4064)
			(end -0.7874 0.4064)
			(stroke
				(width 0.1524)
				(type default)
			)
			(layer "F.SilkS")
		)
		(fp_poly
			(pts
				(xy -0.508 0.2794) (xy -0.508 0.2286) (xy -0.635 0.2286) (xy -0.635 -0.254) (xy -0.5334 -0.254)
				(xy -0.5334 -0.2794) (xy 0.5334 -0.2794) (xy 0.5334 -0.254) (xy 0.635 -0.254) (xy 0.635 0.254) (xy 0.5334 0.254)
				(xy 0.5334 0.2794)
			)
			(stroke
				(width 0)
				(type default)
			)
			(fill no)
			(layer "F.CrtYd")
		)
		(pad "1" smd rect
			(at 0.40005 0)
			(size 0.4572 0.508)
			(layers "F.Cu" "F.Mask" "F.Paste")
			(net "PSU1_RESET")
		)
		(pad "2" smd rect
			(at -0.40005 0)
			(size 0.4572 0.508)
			(layers "F.Cu" "F.Mask" "F.Paste")
			(net "GND")
		)
	)
	(footprint ""
		(layer "F.Cu")
		(at 4.186936 -395.410436 90)
		(property "Reference" "R151"
			(at -4.41071 0.023114 90)
			(unlocked yes)
			(layer "F.SilkS")
			(effects
				(font
					(size 0.7874 0.5842)
					(thickness 0.1524)
				)
				(justify left)
			)
		)
		(property "Value" ""
			(at 0 0 90)
			(layer "F.Fab")
			(effects
				(font
					(size 1.27 1.27)
				)
			)
		)
		(duplicate_pad_numbers_are_jumpers no)
		(fp_line
			(start 0.7874 -0.4064)
			(end 0.7874 0.4064)
			(stroke
				(width 0.1524)
				(type default)
			)
			(layer "F.SilkS")
		)
		(fp_line
			(start -0.7874 -0.4064)
			(end 0.7874 -0.4064)
			(stroke
				(width 0.1524)
				(type default)
			)
			(layer "F.SilkS")
		)
		(fp_line
			(start 0.7874 0.4064)
			(end -0.7874 0.4064)
			(stroke
				(width 0.1524)
				(type default)
			)
			(layer "F.SilkS")
		)
		(fp_line
			(start -0.7874 0.4064)
			(end -0.7874 -0.4064)
			(stroke
				(width 0.1524)
				(type default)
			)
			(layer "F.SilkS")
		)
		(fp_poly
			(pts
				(xy -0.508 0.2794) (xy -0.508 0.2286) (xy -0.635 0.2286) (xy -0.635 -0.254) (xy -0.5334 -0.254)
				(xy -0.5334 -0.2794) (xy 0.5334 -0.2794) (xy 0.5334 -0.254) (xy 0.635 -0.254) (xy 0.635 0.254) (xy 0.5334 0.254)
				(xy 0.5334 0.2794)
			)
			(stroke
				(width 0)
				(type default)
			)
			(fill no)
			(layer "F.CrtYd")
		)
		(pad "1" smd rect
			(at 0.40005 0 90)
			(size 0.4572 0.508)
			(layers "F.Cu" "F.Mask" "F.Paste")
			(net "N42132545")
		)
		(pad "2" smd rect
			(at -0.40005 0 90)
			(size 0.4572 0.508)
			(layers "F.Cu" "F.Mask" "F.Paste")
			(net "GND")
		)
	)
)
